# T6G (Grand Teton) — schematic netlist excerpt (pin names and nets, part order shuffled) for the footprints in the layout excerpt that follows; sources: Cadence DE-HDL packaged netlist, KiCad conversion of 04192023_DAF0TMB3IC0_F0TG_MB_C_brd_V02_OCP.brd

U42  PI3CSW12ZUAEX  IC  pkg UQFN10_0-5_2X1-5  page 186
  \1d+\  = SMB_RT_CPU1_P1_ROM_MUX_1D_SCL
  \1d-\  = SMB_RT_CPU1_P1_ROM_MUX_1D_SDA
  \2d+\  = SMB_RT_CPU1_P1_ROM_MUX_2D_SCL
  \2d-\  = SMB_RT_CPU1_P1_ROM_MUX_2D_SDA
  GND  = GND
  \oe#\  = RT_ROM_MUX2_OE_N
  \d-\  = SMB_RT_CPU1_P1_ROM_R_SDA
  \d+\  = SMB_RT_CPU1_P1_ROM_R_SCL
  S  = FM_SMB_RT_ROM_MUX2_SEL
  VDD  = P3V3_AUX

R6724  Q_RES  4.7K 5% EMPTY  pkg 0201LF  page 320 : A = P1V8_CPU1_RT_1D ; B = RST_RT_CPU1_P0_RESET_R_N

(kicad_pcb
	(version 20260206)
	(generator "pcbnew")
	(generator_version "10.0")
	(general
		(thickness 1.6)
		(legacy_teardrops no)
	)
	(paper "A4")
	(title_block
		(title "04192023_DAF0TMB3IC0_F0TG_MB_C_brd_V02_OCP.brd")
		(comment 1 "Grand Teton / footprints 1343-1344 of 8354")
	)
	(layers
		(0 "F.Cu" signal "TOP")
		(4 "In1.Cu" signal "GND")
		(6 "In2.Cu" signal "IN1")
		(8 "In3.Cu" signal "GND1")
		(10 "In4.Cu" signal "IN2")
		(12 "In5.Cu" signal "GND2")
		(14 "In6.Cu" signal "IN3")
		(16 "In7.Cu" signal "GND3")
		(18 "In8.Cu" signal "VCC")
		(20 "In9.Cu" signal "VCC1")
		(22 "In10.Cu" signal "GND4")
		(24 "In11.Cu" signal "IN4")
		(26 "In12.Cu" signal "GND5")
		(28 "In13.Cu" signal "IN5")
		(30 "In14.Cu" signal "GND6")
		(32 "In15.Cu" signal "IN6")
		(34 "In16.Cu" signal "GND7")
		(2 "B.Cu" signal "BOTTOM")
		(9 "F.Adhes" user "F.Adhesive")
		(11 "B.Adhes" user "B.Adhesive")
		(13 "F.Paste" user "Package Geometry/Pastemask Top")
		(15 "B.Paste" user "Package Geometry/Pastemask Bottom")
		(5 "F.SilkS" user "Ref Des/Silkscreen Top")
		(7 "B.SilkS" user "Ref Des/Silkscreen Bottom")
		(1 "F.Mask" user "Board Geometry/Soldermask Top")
		(3 "B.Mask" user "Board Geometry/Soldermask Bottom")
		(17 "Dwgs.User" user "User.Drawings")
		(19 "Cmts.User" user "User.Comments")
		(21 "Eco1.User" user "User.Eco1")
		(23 "Eco2.User" user "User.Eco2")
		(25 "Edge.Cuts" user "Board Geometry/Outline")
		(27 "Margin" user)
		(31 "F.CrtYd" user "Package Geometry/Place Bound Top")
		(29 "B.CrtYd" user "Package Geometry/Place Bound Bottom")
		(35 "F.Fab" user "Ref Des/Assembly Top")
		(33 "B.Fab" user "Ref Des/Assembly Bottom")
	)
	(footprint ""
		(layer "F.Cu")
		(at 115.389152 -401.353782 180)
		(property "Reference" "U42"
			(at -0.873252 -3.739642 0)
			(unlocked yes)
			(layer "F.SilkS")
			(effects
				(font
					(size 0.7874 0.5842)
					(thickness 0.1524)
				)
			)
		)
		(property "Value" ""
			(at 0 0 180)
			(layer "F.Fab")
			(effects
				(font
					(size 1.27 1.27)
				)
			)
		)
		(duplicate_pad_numbers_are_jumpers no)
		(fp_line
			(start 1.03378 1.284478)
			(end -1.03378 1.284478)
			(stroke
				(width 0.1524)
				(type default)
			)
			(layer "F.SilkS")
		)
		(fp_line
			(start 1.03378 -1.284478)
			(end 1.03378 1.284478)
			(stroke
				(width 0.1524)
				(type default)
			)
			(layer "F.SilkS")
		)
		(fp_line
			(start -1.03378 1.284478)
			(end -1.03378 -1.284478)
			(stroke
				(width 0.1524)
				(type default)
			)
			(layer "F.SilkS")
		)
		(fp_line
			(start -1.03378 -1.284478)
			(end 1.03378 -1.284478)
			(stroke
				(width 0.1524)
				(type default)
			)
			(layer "F.SilkS")
		)
		(fp_poly
			(pts
				(xy -1.176274 -0.652272) (xy -1.478788 -0.047244) (xy -1.841754 -0.531114)
			)
			(stroke
				(width 0)
				(type default)
			)
			(fill yes)
			(layer "F.SilkS")
		)
		(fp_line
			(start 0.774954 1.02489)
			(end -0.774954 1.02489)
			(stroke
				(width 0.1)
				(type default)
			)
			(layer "F.Fab")
		)
		(fp_line
			(start 0.774954 -1.02489)
			(end 0.774954 1.02489)
			(stroke
				(width 0.1)
				(type default)
			)
			(layer "F.Fab")
		)
		(fp_line
			(start -0.774954 1.02489)
			(end -0.774954 -1.02489)
			(stroke
				(width 0.1)
				(type default)
			)
			(layer "F.Fab")
		)
		(fp_line
			(start -0.774954 -1.02489)
			(end 0.774954 -1.02489)
			(stroke
				(width 0.1)
				(type default)
			)
			(layer "F.Fab")
		)
		(fp_poly
			(pts
				(xy -1.201674 -0.750062) (xy -1.806702 -0.447548) (xy -1.806702 -1.052576)
			)
			(stroke
				(width 0)
				(type default)
			)
			(fill yes)
			(layer "F.Fab")
		)
		(pad "1" smd rect
			(at -0.64008 -0.750062 270)
			(size 0.3048 0.5334)
			(layers "F.Cu" "F.Mask" "F.Paste")
			(net "SMB_RT_CPU1_P1_ROM_MUX_1D_SCL")
		)
		(pad "2" smd rect
			(at -0.64008 -0.249936 270)
			(size 0.254 0.5334)
			(layers "F.Cu" "F.Mask" "F.Paste")
			(net "SMB_RT_CPU1_P1_ROM_MUX_1D_SDA")
		)
		(pad "3" smd rect
			(at -0.64008 0.249936 270)
			(size 0.254 0.5334)
			(layers "F.Cu" "F.Mask" "F.Paste")
			(net "SMB_RT_CPU1_P1_ROM_MUX_2D_SCL")
		)
		(pad "4" smd rect
			(at -0.64008 0.750062 270)
			(size 0.3048 0.5334)
			(layers "F.Cu" "F.Mask" "F.Paste")
			(net "SMB_RT_CPU1_P1_ROM_MUX_2D_SDA")
		)
		(pad "5" smd rect
			(at 0 0.839978 180)
			(size 0.3302 0.635)
			(layers "F.Cu" "F.Mask" "F.Paste")
			(net "GND")
		)
		(pad "6" smd rect
			(at 0.64008 0.750062 270)
			(size 0.3048 0.5334)
			(layers "F.Cu" "F.Mask" "F.Paste")
			(net "RT_ROM_MUX2_OE_N")
		)
		(pad "7" smd rect
			(at 0.64008 0.249936 270)
			(size 0.254 0.5334)
			(layers "F.Cu" "F.Mask" "F.Paste")
			(net "SMB_RT_CPU1_P1_ROM_R_SDA")
		)
		(pad "8" smd rect
			(at 0.64008 -0.249936 270)
			(size 0.254 0.5334)
			(layers "F.Cu" "F.Mask" "F.Paste")
			(net "SMB_RT_CPU1_P1_ROM_R_SCL")
		)
		(pad "9" smd rect
			(at 0.64008 -0.750062 270)
			(size 0.3048 0.5334)
			(layers "F.Cu" "F.Mask" "F.Paste")
			(net "FM_SMB_RT_ROM_MUX2_SEL")
		)
		(pad "10" smd rect
			(at 0 -0.839978 180)
			(size 0.3302 0.635)
			(layers "F.Cu" "F.Mask" "F.Paste")
			(net "P3V3_AUX")
		)
	)
	(footprint ""
		(layer "F.Cu")
		(at 40.386 -389.0264 -90)
		(property "Reference" "R6724"
			(at 0 0 270)
			(layer "F.SilkS")
			(hide yes)
			(effects
				(font
					(size 1.27 1.27)
				)
			)
		)
		(property "Value" ""
			(at 0 0 270)
			(layer "F.Fab")
			(effects
				(font
					(size 1.27 1.27)
				)
			)
		)
		(duplicate_pad_numbers_are_jumpers no)
		(fp_line
			(start -0.32512 0.175006)
			(end -0.32512 -0.175006)
			(stroke
				(width 0.1)
				(type default)
			)
			(layer "F.Fab")
		)
		(fp_line
			(start 0.32512 0.175006)
			(end -0.32512 0.175006)
			(stroke
				(width 0.1)
				(type default)
			)
			(layer "F.Fab")
		)
		(fp_line
			(start -0.32512 -0.175006)
			(end 0.32512 -0.175006)
			(stroke
				(width 0.1)
				(type default)
			)
			(layer "F.Fab")
		)
		(fp_line
			(start 0.32512 -0.175006)
			(end 0.32512 0.175006)
			(stroke
				(width 0.1)
				(type default)
			)
			(layer "F.Fab")
		)
		(pad "1" smd rect
			(at -0.2667 0 270)
			(size 0.3048 0.381)
			(layers "F.Cu" "F.Mask" "F.Paste")
			(net "P1V8_CPU1_RT_1D")
		)
		(pad "2" smd rect
			(at 0.2667 0 90)
			(size 0.3048 0.381)
			(layers "F.Cu" "F.Mask" "F.Paste")
			(net "RST_RT_CPU1_P0_RESET_R_N")
		)
	)
)
